# BASEBOARD_FAB2 (Tioga Pass) — schematic netlist excerpt (pin names and nets, part order shuffled) for the footprints in the layout excerpt that follows; sources: Cadence DE-HDL packaged netlist, KiCad conversion of Wiwynn_Tioga_Pass_MB.brd

RM8D1  STANDOFF  SO  pkg TH1  page 184 : IO1 = GND
C4D7  CAP  1.0UF 16V 10% X6S  pkg 0402  page 203 : A = VR_PVCCIN_CPU0_PH4_VCIN ; B = GND
R7G18  RES  0.0 5% EMPTY  pkg 0402  page 189 : A = JTAG_PCH_PLD_TDI ; B = JTAG_TDI

(kicad_pcb
	(version 20260206)
	(generator "pcbnew")
	(generator_version "10.0")
	(general
		(thickness 1.6)
		(legacy_teardrops no)
	)
	(paper "A4")
	(title_block
		(title "Wiwynn_Tioga_Pass_MB.brd")
		(comment 1 "Tioga Pass / footprints 845-847 of 4770")
	)
	(layers
		(0 "F.Cu" signal "TOP")
		(4 "In1.Cu" signal "L2GND")
		(6 "In2.Cu" signal "L3")
		(8 "In3.Cu" signal "L4GND")
		(10 "In4.Cu" signal "L5")
		(12 "In5.Cu" signal "L6GND")
		(14 "In6.Cu" signal "L7VCC")
		(16 "In7.Cu" signal "L8VCC")
		(18 "In8.Cu" signal "L9GND")
		(20 "In9.Cu" signal "L10")
		(22 "In10.Cu" signal "L11GND")
		(24 "In11.Cu" signal "L12")
		(26 "In12.Cu" signal "L13GND")
		(2 "B.Cu" signal "BOTTOM")
		(9 "F.Adhes" user "F.Adhesive")
		(11 "B.Adhes" user "B.Adhesive")
		(13 "F.Paste" user "Package Geometry/Pastemask Top")
		(15 "B.Paste" user "Package Geometry/Pastemask Bottom")
		(5 "F.SilkS" user "Ref Des/Silkscreen Top")
		(7 "B.SilkS" user "Ref Des/Silkscreen Bottom")
		(1 "F.Mask" user "Board Geometry/Soldermask Top")
		(3 "B.Mask" user "Board Geometry/Soldermask Bottom")
		(17 "Dwgs.User" user "User.Drawings")
		(19 "Cmts.User" user "User.Comments")
		(21 "Eco1.User" user "User.Eco1")
		(23 "Eco2.User" user "User.Eco2")
		(25 "Edge.Cuts" user "Board Geometry/Outline")
		(27 "Margin" user)
		(31 "F.CrtYd" user "Package Geometry/Place Bound Top")
		(29 "B.CrtYd" user "Package Geometry/Place Bound Bottom")
		(35 "F.Fab" user "Ref Des/Assembly Top")
		(33 "B.Fab" user "Ref Des/Assembly Bottom")
	)
	(footprint ""
		(layer "F.Cu")
		(at 197.19798 -77.216 -90)
		(property "Reference" "C4D7"
			(at -0.8382 -0.67818 270)
			(unlocked yes)
			(layer "F.SilkS")
			(effects
				(font
					(size 0.4064 0.254)
					(thickness 0.1524)
				)
				(justify left)
			)
		)
		(property "Value" ""
			(at 0 0 270)
			(layer "F.Fab")
			(effects
				(font
					(size 1.27 1.27)
				)
			)
		)
		(duplicate_pad_numbers_are_jumpers no)
		(fp_poly
			(pts
				(xy 0.3048 -0.1016) (xy 0.3048 0.9906) (xy -0.3048 0.9906) (xy -0.3048 -0.1016)
			)
			(stroke
				(width 0)
				(type default)
			)
			(fill no)
			(layer "F.CrtYd")
		)
		(fp_line
			(start -0.3048 0.9906)
			(end 0.3048 0.9906)
			(stroke
				(width 0.1)
				(type default)
			)
			(layer "F.Fab")
		)
		(fp_line
			(start 0.3048 0.9906)
			(end 0.3048 -0.1016)
			(stroke
				(width 0.1)
				(type default)
			)
			(layer "F.Fab")
		)
		(fp_line
			(start -0.3048 -0.1016)
			(end -0.3048 0.9906)
			(stroke
				(width 0.1)
				(type default)
			)
			(layer "F.Fab")
		)
		(fp_line
			(start 0.3048 -0.1016)
			(end -0.3048 -0.1016)
			(stroke
				(width 0.1)
				(type default)
			)
			(layer "F.Fab")
		)
		(pad "1" smd rect
			(at 0 0 270)
			(size 0.508 0.508)
			(layers "F.Cu" "F.Mask" "F.Paste")
			(net "VR_PVCCIN_CPU0_PH4_VCIN")
		)
		(pad "2" smd rect
			(at 0 0.889 270)
			(size 0.508 0.508)
			(layers "F.Cu" "F.Mask" "F.Paste")
			(net "GND")
		)
		(zone
			(layer "F.Cu")
			(hatch none 0.5)
			(connect_pads
				(clearance 0)
			)
			(min_thickness 0.25)
			(keepout
				(tracks not_allowed)
				(vias allowed)
				(pads allowed)
				(copperpour not_allowed)
				(footprints allowed)
			)
			(placement
				(enabled no)
				(sheetname "")
			)
			(fill
				(thermal_gap 0.5)
				(thermal_bridge_width 0.5)
				(island_removal_mode 0)
			)
			(polygon
				(pts
					(xy 196.56298 -77.47) (xy 196.56298 -76.962) (xy 196.94398 -76.962) (xy 196.94398 -77.47)
				)
			)
		)
		(zone
			(layer "F.Cu")
			(hatch none 0.5)
			(connect_pads
				(clearance 0)
			)
			(min_thickness 0.25)
			(keepout
				(tracks allowed)
				(vias not_allowed)
				(pads allowed)
				(copperpour not_allowed)
				(footprints allowed)
			)
			(placement
				(enabled no)
				(sheetname "")
			)
			(fill
				(thermal_gap 0.5)
				(thermal_bridge_width 0.5)
				(island_removal_mode 0)
			)
			(polygon
				(pts
					(xy 196.94398 -77.47) (xy 196.94398 -76.962) (xy 196.56298 -76.962) (xy 196.56298 -77.47)
				)
			)
		)
	)
	(footprint ""
		(layer "F.Cu")
		(at 409.719526 -76.883768)
		(property "Reference" "RM8D1"
			(at -4.496562 1.28778 90)
			(unlocked yes)
			(layer "F.SilkS")
			(effects
				(font
					(size 0.7874 0.5842)
					(thickness 0.1524)
				)
				(justify left)
			)
		)
		(property "Value" ""
			(at 0 0 0)
			(layer "F.Fab")
			(effects
				(font
					(size 1.27 1.27)
				)
			)
		)
		(duplicate_pad_numbers_are_jumpers no)
		(fp_poly
			(pts
				(arc
					(start 3.5052 0)
					(mid -3.5052 0)
					(end 3.5052 0)
				)
			)
			(stroke
				(width 0)
				(type default)
			)
			(fill yes)
			(layer "F.Paste")
		)
		(fp_poly
			(pts
				(arc
					(start 3.050032 0)
					(mid -3.050032 0)
					(end 3.050032 0)
				)
			)
			(stroke
				(width 0)
				(type default)
			)
			(fill no)
			(layer "F.CrtYd")
		)
		(fp_circle
			(center 0 0)
			(end 3.050032 0)
			(stroke
				(width 0.1)
				(type default)
			)
			(fill no)
			(layer "F.Fab")
		)
		(pad "1" thru_hole circle
			(at 0 0)
			(size 7.0104 7.0104)
			(drill 4.4958)
			(layers "*.Cu" "*.Mask")
			(remove_unused_layers no)
			(net "GND")
			(clearance -0.9398)
		)
	)
	(footprint ""
		(layer "F.Cu")
		(at 389.636 -0.254)
		(property "Reference" "R7G18"
			(at 0 0 0)
			(layer "F.SilkS")
			(hide yes)
			(effects
				(font
					(size 1.27 1.27)
				)
			)
		)
		(property "Value" ""
			(at 0 0 0)
			(layer "F.Fab")
			(effects
				(font
					(size 1.27 1.27)
				)
			)
		)
		(duplicate_pad_numbers_are_jumpers no)
		(fp_poly
			(pts
				(xy -0.2794 -0.1016) (xy 0.2794 -0.1016) (xy 0.2794 0.9906) (xy -0.2794 0.9906)
			)
			(stroke
				(width 0)
				(type default)
			)
			(fill no)
			(layer "F.CrtYd")
		)
		(fp_line
			(start -0.2794 -0.1016)
			(end -0.2794 0.9906)
			(stroke
				(width 0.1)
				(type default)
			)
			(layer "F.Fab")
		)
		(fp_line
			(start -0.2794 0.9906)
			(end 0.2794 0.9906)
			(stroke
				(width 0.1)
				(type default)
			)
			(layer "F.Fab")
		)
		(fp_line
			(start 0.2794 -0.1016)
			(end -0.2794 -0.1016)
			(stroke
				(width 0.1)
				(type default)
			)
			(layer "F.Fab")
		)
		(fp_line
			(start 0.2794 0.9906)
			(end 0.2794 -0.1016)
			(stroke
				(width 0.1)
				(type default)
			)
			(layer "F.Fab")
		)
		(pad "1" smd rect
			(at 0 0)
			(size 0.508 0.508)
			(layers "F.Cu" "F.Mask" "F.Paste")
			(net "JTAG_PCH_PLD_TDI")
		)
		(pad "2" smd rect
			(at 0 0.889)
			(size 0.508 0.508)
			(layers "F.Cu" "F.Mask" "F.Paste")
			(net "JTAG_TDI")
		)
		(zone
			(layer "F.Cu")
			(hatch none 0.5)
			(connect_pads
				(clearance 0)
			)
			(min_thickness 0.25)
			(keepout
				(tracks allowed)
				(vias not_allowed)
				(pads allowed)
				(copperpour not_allowed)
				(footprints allowed)
			)
			(placement
				(enabled no)
				(sheetname "")
			)
			(fill
				(thermal_gap 0.5)
				(thermal_bridge_width 0.5)
				(island_removal_mode 0)
			)
			(polygon
				(pts
					(xy 389.382 0) (xy 389.89 0) (xy 389.89 0.381) (xy 389.382 0.381)
				)
			)
		)
		(zone
			(layer "F.Cu")
			(hatch none 0.5)
			(connect_pads
				(clearance 0)
			)
			(min_thickness 0.25)
			(keepout
				(tracks not_allowed)
				(vias allowed)
				(pads allowed)
				(copperpour not_allowed)
				(footprints allowed)
			)
			(placement
				(enabled no)
				(sheetname "")
			)
			(fill
				(thermal_gap 0.5)
				(thermal_bridge_width 0.5)
				(island_removal_mode 0)
			)
			(polygon
				(pts
					(xy 389.382 0.381) (xy 389.89 0.381) (xy 389.89 0) (xy 389.382 0)
				)
			)
		)
	)
)
